(kicad_pcb
	(version 20241229)
	(generator "pcbnew")
	(generator_version "9.0")
	(general
		(thickness 1.61)
		(legacy_teardrops no)
	)
	(paper "A3")
	(title_block
		(title "RDIMM DDR5 Tester")
		(date "2026-05-21")
		(rev "2.2.0")
		(company "Antmicro")
		(comment 9 "footprints 445-449 of 796")
	)
	(layers
		(0 "F.Cu" signal)
		(4 "In1.Cu" power)
		(6 "In2.Cu" mixed)
		(8 "In3.Cu" power)
		(10 "In4.Cu" mixed)
		(12 "In5.Cu" power)
		(14 "In6.Cu" mixed)
		(16 "In7.Cu" power)
		(18 "In8.Cu" power)
		(20 "In9.Cu" mixed)
		(22 "In10.Cu" power)
		(2 "B.Cu" signal)
		(9 "F.Adhes" user "F.Adhesive")
		(11 "B.Adhes" user "B.Adhesive")
		(13 "F.Paste" user)
		(15 "B.Paste" user)
		(5 "F.SilkS" user "F.Silkscreen")
		(7 "B.SilkS" user "B.Silkscreen")
		(1 "F.Mask" user)
		(3 "B.Mask" user)
		(17 "Dwgs.User" user "User.Drawings")
		(19 "Cmts.User" user "User.Comments")
		(21 "Eco1.User" user "User.Eco1")
		(23 "Eco2.User" user "User.Eco2")
		(25 "Edge.Cuts" user)
		(27 "Margin" user)
		(31 "F.CrtYd" user "F.Courtyard")
		(29 "B.CrtYd" user "B.Courtyard")
		(35 "F.Fab" user)
		(33 "B.Fab" user)
	)
	(footprint "antmicro-footprints:R_0402_1005Metric"
		(layer "B.Cu")
		(at 208.275 154.19 -90)
		(descr "Resistor SMD 0402")
		(tags "resistor SMD 0402")
		(property "Reference" "R20"
			(at 1.36 -0.475 90)
			(layer "B.SilkS")
			(effects
				(font
					(size 0.7 0.7)
					(thickness 0.15)
				)
				(justify left bottom mirror)
			)
		)
		(property "Value" "R_4k7_0402"
			(at -1.011843 -1.772047 90)
			(layer "B.Fab")
			(effects
				(font
					(size 0.7 0.7)
					(thickness 0.15)
				)
				(justify left bottom mirror)
			)
		)
		(property "Datasheet" "https://www.bourns.com/docs/product-datasheets/cr.pdf"
			(at 0 0 270)
			(layer "F.Fab")
			(hide yes)
			(effects
				(font
					(size 1.27 1.27)
					(thickness 0.15)
				)
			)
		)
		(property "MPN" "CR0402-FX-4701GLF"
			(at 0 0 270)
			(unlocked yes)
			(layer "B.Fab")
			(hide yes)
			(effects
				(font
					(size 1 1)
					(thickness 0.15)
				)
				(justify mirror)
			)
		)
		(property "Manufacturer" "Bourns"
			(at 0 0 270)
			(unlocked yes)
			(layer "B.Fab")
			(hide yes)
			(effects
				(font
					(size 1 1)
					(thickness 0.15)
				)
				(justify mirror)
			)
		)
		(property "License" "Apache-2.0"
			(at 0 0 270)
			(unlocked yes)
			(layer "B.Fab")
			(hide yes)
			(effects
				(font
					(size 1 1)
					(thickness 0.15)
				)
				(justify mirror)
			)
		)
		(property "Author" "Antmicro"
			(at 0 0 270)
			(unlocked yes)
			(layer "B.Fab")
			(hide yes)
			(effects
				(font
					(size 1 1)
					(thickness 0.15)
				)
				(justify mirror)
			)
		)
		(property "Val" "4k7"
			(at 0 0 270)
			(unlocked yes)
			(layer "B.Fab")
			(hide yes)
			(effects
				(font
					(size 1 1)
					(thickness 0.15)
				)
				(justify mirror)
			)
		)
		(property "Tolerance" "1%"
			(at 0 0 270)
			(unlocked yes)
			(layer "B.Fab")
			(hide yes)
			(effects
				(font
					(size 1 1)
					(thickness 0.15)
				)
				(justify mirror)
			)
		)
		(sheetname "/FPGA Config/")
		(sheetfile "fpga-config.kicad_sch")
		(attr smd)
		(fp_rect
			(start -0.925 0.47)
			(end 0.925 -0.47)
			(stroke
				(width 0.05)
				(type default)
			)
			(fill no)
			(layer "B.CrtYd")
		)
		(fp_rect
			(start -0.5 0.25)
			(end 0.5 -0.25)
			(stroke
				(width 0.15)
				(type solid)
			)
			(fill no)
			(layer "B.Fab")
		)
		(fp_text user "License: Apache-2.0"
			(at -0.95 -5.169 90)
			(layer "B.Fab")
			(effects
				(font
					(size 0.7 0.7)
					(thickness 0.15)
				)
				(justify left bottom mirror)
			)
		)
		(fp_text user "Author: Antmicro"
			(at -0.95 -4.169 90)
			(layer "B.Fab")
			(effects
				(font
					(size 0.7 0.7)
					(thickness 0.15)
				)
				(justify left bottom mirror)
			)
		)
		(fp_text user "${REFERENCE}"
			(at -0.95 -3.168 90)
			(layer "B.Fab")
			(effects
				(font
					(size 0.7 0.7)
					(thickness 0.15)
				)
				(justify left bottom mirror)
			)
		)
		(pad "1" smd roundrect
			(at -0.48 0 270)
			(size 0.59 0.64)
			(layers "B.Cu" "B.Mask" "B.Paste")
			(roundrect_rratio 0.25)
			(net 151 "+3V3")
			(pintype "passive")
		)
		(pad "2" smd roundrect
			(at 0.48 0 270)
			(size 0.59 0.64)
			(layers "B.Cu" "B.Mask" "B.Paste")
			(roundrect_rratio 0.25)
			(net 477 "/FPGA Config/~{ALARM}")
			(pintype "passive")
		)
	)
	(footprint "antmicro-footprints:C_0603_1608Metric"
		(layer "B.Cu")
		(at 230.154999 172.080002 90)
		(descr "Capacitor SMD 0603")
		(tags "capacitor 0603")
		(property "Reference" "C272"
			(at -4.069998 0.320001 90)
			(layer "B.SilkS")
			(effects
				(font
					(size 0.7 0.7)
					(thickness 0.15)
				)
				(justify right bottom mirror)
			)
		)
		(property "Value" "C_22u_0603"
			(at -1.42757 -1.770288 90)
			(layer "B.Fab")
			(effects
				(font
					(size 0.7 0.7)
					(thickness 0.15)
				)
				(justify right bottom mirror)
			)
		)
		(property "Datasheet" "https://www.murata.com/products/productdetail?partno=GRM188R60J226MEA0%23"
			(at 0 0 90)
			(layer "F.Fab")
			(hide yes)
			(effects
				(font
					(size 1.27 1.27)
					(thickness 0.15)
				)
			)
		)
		(property "Manufacturer" "Murata"
			(at 0 0 90)
			(unlocked yes)
			(layer "B.Fab")
			(hide yes)
			(effects
				(font
					(size 1 1)
					(thickness 0.15)
				)
				(justify mirror)
			)
		)
		(property "MPN" "GRM188R60J226MEA0D"
			(at 0 0 90)
			(unlocked yes)
			(layer "B.Fab")
			(hide yes)
			(effects
				(font
					(size 1 1)
					(thickness 0.15)
				)
				(justify mirror)
			)
		)
		(property "Val" "22u"
			(at 0 0 90)
			(unlocked yes)
			(layer "B.Fab")
			(hide yes)
			(effects
				(font
					(size 1 1)
					(thickness 0.15)
				)
				(justify mirror)
			)
		)
		(property "License" "Apache-2.0"
			(at 0 0 90)
			(unlocked yes)
			(layer "B.Fab")
			(hide yes)
			(effects
				(font
					(size 1 1)
					(thickness 0.15)
				)
				(justify mirror)
			)
		)
		(property "Author" "Antmicro"
			(at 0 0 90)
			(unlocked yes)
			(layer "B.Fab")
			(hide yes)
			(effects
				(font
					(size 1 1)
					(thickness 0.15)
				)
				(justify mirror)
			)
		)
		(property "Voltage" ""
			(at 0 0 90)
			(unlocked yes)
			(layer "B.Fab")
			(hide yes)
			(effects
				(font
					(size 1 1)
					(thickness 0.15)
				)
				(justify mirror)
			)
		)
		(property "Dielectric" ""
			(at 0 0 90)
			(unlocked yes)
			(layer "B.Fab")
			(hide yes)
			(effects
				(font
					(size 1 1)
					(thickness 0.15)
				)
				(justify mirror)
			)
		)
		(sheetname "/Supply/DC-DC VCCINT/")
		(sheetfile "dc-dc-vccint.kicad_sch")
		(attr smd)
		(fp_line
			(start -0.15 -0.4)
			(end 0.15 -0.4)
			(stroke
				(width 0.15)
				(type solid)
			)
			(layer "B.SilkS")
		)
		(fp_line
			(start -0.15 0.4)
			(end 0.15 0.4)
			(stroke
				(width 0.15)
				(type solid)
			)
			(layer "B.SilkS")
		)
		(fp_rect
			(start -1.25 0.65)
			(end 1.25 -0.65)
			(stroke
				(width 0.05)
				(type solid)
			)
			(fill no)
			(layer "B.CrtYd")
		)
		(fp_rect
			(start -0.8 0.4)
			(end 0.8 -0.4)
			(stroke
				(width 0.15)
				(type solid)
			)
			(fill no)
			(layer "B.Fab")
		)
		(fp_text user "License: Apache-2.0"
			(at -1.682 -5.895 270)
			(layer "B.Fab")
			(effects
				(font
					(size 0.7 0.7)
					(thickness 0.15)
				)
				(justify left bottom mirror)
			)
		)
		(fp_text user "Author: Antmicro"
			(at -1.682 -4.894 270)
			(layer "B.Fab")
			(effects
				(font
					(size 0.7 0.7)
					(thickness 0.15)
				)
				(justify left bottom mirror)
			)
		)
		(fp_text user "${REFERENCE}"
			(at -1.682 -3.895 270)
			(layer "B.Fab")
			(effects
				(font
					(size 0.7 0.7)
					(thickness 0.15)
				)
				(justify left bottom mirror)
			)
		)
		(pad "1" smd roundrect
			(at -0.7 0 90)
			(size 0.8 1)
			(layers "B.Cu" "B.Mask" "B.Paste")
			(roundrect_rratio 0.2)
			(net 1 "GND")
			(pintype "passive")
		)
		(pad "2" smd roundrect
			(at 0.7 0 90)
			(size 0.8 1)
			(layers "B.Cu" "B.Mask" "B.Paste")
			(roundrect_rratio 0.2)
			(net 224 "/Supply/DC-DC VCCINT/0V85_REG1")
			(pintype "passive")
		)
	)
	(footprint "antmicro-footprints:R_0402_1005Metric"
		(layer "B.Cu")
		(at 203.25 137.0645 180)
		(descr "Resistor SMD 0402")
		(tags "resistor SMD 0402")
		(property "Reference" "R256"
			(at 2.35 0 0)
			(layer "B.SilkS")
			(effects
				(font
					(size 0.7 0.7)
					(thickness 0.15)
				)
				(justify mirror)
			)
		)
		(property "Value" "R_0R_0402"
			(at -1.011843 -1.772047 0)
			(layer "B.Fab")
			(effects
				(font
					(size 0.7 0.7)
					(thickness 0.15)
				)
				(justify left bottom mirror)
			)
		)
		(property "Datasheet" "https://industrial.panasonic.com/cdbs/www-data/pdf/RDA0000/AOA0000C301.pdf"
			(at 0 0 0)
			(layer "B.Fab")
			(hide yes)
			(effects
				(font
					(size 1.27 1.27)
					(thickness 0.15)
				)
				(justify mirror)
			)
		)
		(property "MPN" "ERJ2GE0R00X"
			(at 0 0 0)
			(unlocked yes)
			(layer "B.Fab")
			(hide yes)
			(effects
				(font
					(size 1 1)
					(thickness 0.15)
				)
				(justify mirror)
			)
		)
		(property "Manufacturer" "Panasonic"
			(at 0 0 0)
			(unlocked yes)
			(layer "B.Fab")
			(hide yes)
			(effects
				(font
					(size 1 1)
					(thickness 0.15)
				)
				(justify mirror)
			)
		)
		(property "License" "Apache-2.0"
			(at 0 0 0)
			(unlocked yes)
			(layer "B.Fab")
			(hide yes)
			(effects
				(font
					(size 1 1)
					(thickness 0.15)
				)
				(justify mirror)
			)
		)
		(property "Author" "Antmicro"
			(at 0 0 0)
			(unlocked yes)
			(layer "B.Fab")
			(hide yes)
			(effects
				(font
					(size 1 1)
					(thickness 0.15)
				)
				(justify mirror)
			)
		)
		(property "Val" "0R"
			(at 0 0 0)
			(unlocked yes)
			(layer "B.Fab")
			(hide yes)
			(effects
				(font
					(size 1 1)
					(thickness 0.15)
				)
				(justify mirror)
			)
		)
		(property "Tolerance" "~"
			(at 0 0 0)
			(unlocked yes)
			(layer "B.Fab")
			(hide yes)
			(effects
				(font
					(size 1 1)
					(thickness 0.15)
				)
				(justify mirror)
			)
		)
		(property "Current" "1A"
			(at 0 0 0)
			(unlocked yes)
			(layer "B.Fab")
			(hide yes)
			(effects
				(font
					(size 1 1)
					(thickness 0.15)
				)
				(justify mirror)
			)
		)
		(sheetname "/FPGA banks HP/")
		(sheetfile "fpga-hp-banks.kicad_sch")
		(attr smd exclude_from_bom dnp)
		(fp_rect
			(start -0.925 0.47)
			(end 0.925 -0.47)
			(stroke
				(width 0.05)
				(type default)
			)
			(fill no)
			(layer "B.CrtYd")
		)
		(fp_rect
			(start -0.5 0.25)
			(end 0.5 -0.25)
			(stroke
				(width 0.15)
				(type solid)
			)
			(fill no)
			(layer "B.Fab")
		)
		(fp_text user "Author: Antmicro"
			(at -0.95 -4.169 0)
			(layer "B.Fab")
			(effects
				(font
					(size 0.7 0.7)
					(thickness 0.15)
				)
				(justify left bottom mirror)
			)
		)
		(fp_text user "License: Apache-2.0"
			(at -0.95 -5.169 0)
			(layer "B.Fab")
			(effects
				(font
					(size 0.7 0.7)
					(thickness 0.15)
				)
				(justify left bottom mirror)
			)
		)
		(fp_text user "${REFERENCE}"
			(at -0.95 -3.168 0)
			(layer "B.Fab")
			(effects
				(font
					(size 0.7 0.7)
					(thickness 0.15)
				)
				(justify left bottom mirror)
			)
		)
		(pad "1" smd roundrect
			(at -0.48 0 180)
			(size 0.59 0.64)
			(layers "B.Cu" "B.Mask" "B.Paste")
			(roundrect_rratio 0.25)
			(net 827 "Net-(R253-Pad1)")
			(pintype "passive")
		)
		(pad "2" smd roundrect
			(at 0.48 0 180)
			(size 0.59 0.64)
			(layers "B.Cu" "B.Mask" "B.Paste")
			(roundrect_rratio 0.25)
			(net 826 "/FPGA banks HP/VREF")
			(pintype "passive")
		)
	)
	(footprint "antmicro-footprints:R_0402_1005Metric"
		(layer "B.Cu")
		(at 110.38 166.95 -90)
		(descr "Resistor SMD 0402")
		(tags "resistor SMD 0402")
		(property "Reference" "R81"
			(at -1.122484 0.772697 90)
			(layer "B.SilkS")
			(effects
				(font
					(size 0.7 0.7)
					(thickness 0.15)
				)
				(justify left bottom mirror)
			)
		)
		(property "Value" "R_1k_0402"
			(at -1.011843 -1.772047 90)
			(layer "B.Fab")
			(effects
				(font
					(size 0.7 0.7)
					(thickness 0.15)
				)
				(justify left bottom mirror)
			)
		)
		(property "Datasheet" "https://www.bourns.com/docs/product-datasheets/cr.pdf"
			(at 0 0 270)
			(layer "F.Fab")
			(hide yes)
			(effects
				(font
					(size 1.27 1.27)
					(thickness 0.15)
				)
			)
		)
		(property "MPN" "CR0402-FX-1001GLF"
			(at 0 0 270)
			(unlocked yes)
			(layer "B.Fab")
			(hide yes)
			(effects
				(font
					(size 1 1)
					(thickness 0.15)
				)
				(justify mirror)
			)
		)
		(property "Manufacturer" "Bourns"
			(at 0 0 270)
			(unlocked yes)
			(layer "B.Fab")
			(hide yes)
			(effects
				(font
					(size 1 1)
					(thickness 0.15)
				)
				(justify mirror)
			)
		)
		(property "License" "Apache-2.0"
			(at 0 0 270)
			(unlocked yes)
			(layer "B.Fab")
			(hide yes)
			(effects
				(font
					(size 1 1)
					(thickness 0.15)
				)
				(justify mirror)
			)
		)
		(property "Author" "Antmicro"
			(at 0 0 270)
			(unlocked yes)
			(layer "B.Fab")
			(hide yes)
			(effects
				(font
					(size 1 1)
					(thickness 0.15)
				)
				(justify mirror)
			)
		)
		(property "Val" "1k"
			(at 0 0 270)
			(unlocked yes)
			(layer "B.Fab")
			(hide yes)
			(effects
				(font
					(size 1 1)
					(thickness 0.15)
				)
				(justify mirror)
			)
		)
		(property "Tolerance" "1%"
			(at 0 0 270)
			(unlocked yes)
			(layer "B.Fab")
			(hide yes)
			(effects
				(font
					(size 1 1)
					(thickness 0.15)
				)
				(justify mirror)
			)
		)
		(sheetname "/HDMI + SD Card/")
		(sheetfile "hdmi-sd-card.kicad_sch")
		(attr smd)
		(fp_rect
			(start -0.925 0.47)
			(end 0.925 -0.47)
			(stroke
				(width 0.05)
				(type default)
			)
			(fill no)
			(layer "B.CrtYd")
		)
		(fp_rect
			(start -0.5 0.25)
			(end 0.5 -0.25)
			(stroke
				(width 0.15)
				(type solid)
			)
			(fill no)
			(layer "B.Fab")
		)
		(fp_text user "${REFERENCE}"
			(at -0.95 -3.168 90)
			(layer "B.Fab")
			(effects
				(font
					(size 0.7 0.7)
					(thickness 0.15)
				)
				(justify left bottom mirror)
			)
		)
		(fp_text user "Author: Antmicro"
			(at -0.95 -4.169 90)
			(layer "B.Fab")
			(effects
				(font
					(size 0.7 0.7)
					(thickness 0.15)
				)
				(justify left bottom mirror)
			)
		)
		(fp_text user "License: Apache-2.0"
			(at -0.95 -5.169 90)
			(layer "B.Fab")
			(effects
				(font
					(size 0.7 0.7)
					(thickness 0.15)
				)
				(justify left bottom mirror)
			)
		)
		(pad "1" smd roundrect
			(at -0.48 0 270)
			(size 0.59 0.64)
			(layers "B.Cu" "B.Mask" "B.Paste")
			(roundrect_rratio 0.25)
			(net 604 "/HDMI + SD Card/HDMI_IN_HPD_CONN")
			(pintype "passive")
		)
		(pad "2" smd roundrect
			(at 0.48 0 270)
			(size 0.59 0.64)
			(layers "B.Cu" "B.Mask" "B.Paste")
			(roundrect_rratio 0.25)
			(net 297 "/HDMI + SD Card/HDMI_IN_5V")
			(pintype "passive")
		)
	)
	(footprint "antmicro-footprints:R_0402_1005Metric"
		(layer "B.Cu")
		(at 111.98 168.37 180)
		(descr "Resistor SMD 0402")
		(tags "resistor SMD 0402")
		(property "Reference" "R82"
			(at -1.122484 -1.48 0)
			(layer "B.SilkS")
			(effects
				(font
					(size 0.7 0.7)
					(thickness 0.15)
				)
				(justify left bottom mirror)
			)
		)
		(property "Value" "R_1k_0402"
			(at -1.011843 -1.772047 0)
			(layer "B.Fab")
			(effects
				(font
					(size 0.7 0.7)
					(thickness 0.15)
				)
				(justify left bottom mirror)
			)
		)
		(property "Datasheet" "https://www.bourns.com/docs/product-datasheets/cr.pdf"
			(at 0 0 180)
			(layer "F.Fab")
			(hide yes)
			(effects
				(font
					(size 1.27 1.27)
					(thickness 0.15)
				)
			)
		)
		(property "MPN" "CR0402-FX-1001GLF"
			(at 0 0 180)
			(unlocked yes)
			(layer "B.Fab")
			(hide yes)
			(effects
				(font
					(size 1 1)
					(thickness 0.15)
				)
				(justify mirror)
			)
		)
		(property "Manufacturer" "Bourns"
			(at 0 0 180)
			(unlocked yes)
			(layer "B.Fab")
			(hide yes)
			(effects
				(font
					(size 1 1)
					(thickness 0.15)
				)
				(justify mirror)
			)
		)
		(property "License" "Apache-2.0"
			(at 0 0 180)
			(unlocked yes)
			(layer "B.Fab")
			(hide yes)
			(effects
				(font
					(size 1 1)
					(thickness 0.15)
				)
				(justify mirror)
			)
		)
		(property "Author" "Antmicro"
			(at 0 0 180)
			(unlocked yes)
			(layer "B.Fab")
			(hide yes)
			(effects
				(font
					(size 1 1)
					(thickness 0.15)
				)
				(justify mirror)
			)
		)
		(property "Val" "1k"
			(at 0 0 180)
			(unlocked yes)
			(layer "B.Fab")
			(hide yes)
			(effects
				(font
					(size 1 1)
					(thickness 0.15)
				)
				(justify mirror)
			)
		)
		(property "Tolerance" "1%"
			(at 0 0 180)
			(unlocked yes)
			(layer "B.Fab")
			(hide yes)
			(effects
				(font
					(size 1 1)
					(thickness 0.15)
				)
				(justify mirror)
			)
		)
		(sheetname "/HDMI + SD Card/")
		(sheetfile "hdmi-sd-card.kicad_sch")
		(attr smd)
		(fp_rect
			(start -0.925 0.47)
			(end 0.925 -0.47)
			(stroke
				(width 0.05)
				(type default)
			)
			(fill no)
			(layer "B.CrtYd")
		)
		(fp_rect
			(start -0.5 0.25)
			(end 0.5 -0.25)
			(stroke
				(width 0.15)
				(type solid)
			)
			(fill no)
			(layer "B.Fab")
		)
		(fp_text user "${REFERENCE}"
			(at -0.95 -3.168 0)
			(layer "B.Fab")
			(effects
				(font
					(size 0.7 0.7)
					(thickness 0.15)
				)
				(justify left bottom mirror)
			)
		)
		(fp_text user "Author: Antmicro"
			(at -0.95 -4.169 0)
			(layer "B.Fab")
			(effects
				(font
					(size 0.7 0.7)
					(thickness 0.15)
				)
				(justify left bottom mirror)
			)
		)
		(fp_text user "License: Apache-2.0"
			(at -0.95 -5.169 0)
			(layer "B.Fab")
			(effects
				(font
					(size 0.7 0.7)
					(thickness 0.15)
				)
				(justify left bottom mirror)
			)
		)
		(pad "1" smd roundrect
			(at -0.48 0 180)
			(size 0.59 0.64)
			(layers "B.Cu" "B.Mask" "B.Paste")
			(roundrect_rratio 0.25)
			(net 506 "Net-(Q18-G)")
			(pintype "passive")
		)
		(pad "2" smd roundrect
			(at 0.48 0 180)
			(size 0.59 0.64)
			(layers "B.Cu" "B.Mask" "B.Paste")
			(roundrect_rratio 0.25)
			(net 297 "/HDMI + SD Card/HDMI_IN_5V")
			(pintype "passive")
		)
	)
)
